# SCM (Grand Teton) — schematic netlist excerpt (pin names and nets, part order shuffled) for the footprints in the layout excerpt that follows; sources: Cadence DE-HDL packaged netlist, KiCad conversion of 12092022_DA0F0TMDCD0_F0T_Management_Board_D_brd_V3_OCP.brd

C209  Q_CAP  18PF 50V 5% C0G  pkg 0402  page 23 : A = V_DACG_IO ; B = GND
R365  Q_RES  120 1% CHIP  pkg 0402LF  page 20 : A = M_BMC_DDR4_MWE_N ; B = P1V2_AUX

(kicad_pcb
	(version 20260206)
	(generator "pcbnew")
	(generator_version "10.0")
	(general
		(thickness 1.6)
		(legacy_teardrops no)
	)
	(paper "A4")
	(title_block
		(title "12092022_DA0F0TMDCD0_F0T_Management_Board_D_brd_V3_OCP.brd")
		(comment 1 "Grand Teton / footprints 785-786 of 1440")
	)
	(layers
		(0 "F.Cu" signal "TOP")
		(4 "In1.Cu" signal "GND")
		(6 "In2.Cu" signal "IN1")
		(8 "In3.Cu" signal "GND1")
		(10 "In4.Cu" signal "IN2")
		(12 "In5.Cu" signal "VCC")
		(14 "In6.Cu" signal "VCC1")
		(16 "In7.Cu" signal "IN3")
		(18 "In8.Cu" signal "GND2")
		(20 "In9.Cu" signal "IN4")
		(22 "In10.Cu" signal "GND3")
		(2 "B.Cu" signal "BOTTOM")
		(9 "F.Adhes" user "F.Adhesive")
		(11 "B.Adhes" user "B.Adhesive")
		(13 "F.Paste" user "Package Geometry/Pastemask Top")
		(15 "B.Paste" user "Package Geometry/Pastemask Bottom")
		(5 "F.SilkS" user "Ref Des/Silkscreen Top")
		(7 "B.SilkS" user "Ref Des/Silkscreen Bottom")
		(1 "F.Mask" user "Board Geometry/Soldermask Top")
		(3 "B.Mask" user "Board Geometry/Soldermask Bottom")
		(17 "Dwgs.User" user "User.Drawings")
		(19 "Cmts.User" user "User.Comments")
		(21 "Eco1.User" user "User.Eco1")
		(23 "Eco2.User" user "User.Eco2")
		(25 "Edge.Cuts" user "Board Geometry/Outline")
		(27 "Margin" user)
		(31 "F.CrtYd" user "Package Geometry/Place Bound Top")
		(29 "B.CrtYd" user "Package Geometry/Place Bound Bottom")
		(35 "F.Fab" user "Ref Des/Assembly Top")
		(33 "B.Fab" user "Ref Des/Assembly Bottom")
	)
	(footprint ""
		(layer "B.Cu")
		(at 31.877 -30.353 -90)
		(property "Reference" "C209"
			(at 0 0 90)
			(layer "B.SilkS")
			(hide yes)
			(effects
				(font
					(size 1.27 1.27)
				)
				(justify mirror)
			)
		)
		(property "Value" ""
			(at 0 0 90)
			(layer "B.Fab")
			(effects
				(font
					(size 1.27 1.27)
				)
				(justify mirror)
			)
		)
		(duplicate_pad_numbers_are_jumpers no)
		(fp_line
			(start -0.7874 0.4064)
			(end 0.7874 0.4064)
			(stroke
				(width 0.1524)
				(type default)
			)
			(layer "B.SilkS")
		)
		(fp_line
			(start 0.7874 0.4064)
			(end 0.7874 -0.4064)
			(stroke
				(width 0.1524)
				(type default)
			)
			(layer "B.SilkS")
		)
		(fp_line
			(start -0.7874 -0.4064)
			(end -0.7874 0.4064)
			(stroke
				(width 0.1524)
				(type default)
			)
			(layer "B.SilkS")
		)
		(fp_line
			(start 0.7874 -0.4064)
			(end -0.7874 -0.4064)
			(stroke
				(width 0.1524)
				(type default)
			)
			(layer "B.SilkS")
		)
		(fp_line
			(start -0.67945 0.3048)
			(end -0.120396 0.3048)
			(stroke
				(width 0.1)
				(type default)
			)
			(layer "B.Fab")
		)
		(fp_line
			(start -0.120396 0.3048)
			(end -0.120396 0.2794)
			(stroke
				(width 0.1)
				(type default)
			)
			(layer "B.Fab")
		)
		(fp_line
			(start 0.12065 0.3048)
			(end 0.67945 0.3048)
			(stroke
				(width 0.1)
				(type default)
			)
			(layer "B.Fab")
		)
		(fp_line
			(start 0.67945 0.3048)
			(end 0.67945 -0.305054)
			(stroke
				(width 0.1)
				(type default)
			)
			(layer "B.Fab")
		)
		(fp_line
			(start -0.120396 0.2794)
			(end 0.12065 0.2794)
			(stroke
				(width 0.1)
				(type default)
			)
			(layer "B.Fab")
		)
		(fp_line
			(start 0.12065 0.2794)
			(end 0.12065 0.3048)
			(stroke
				(width 0.1)
				(type default)
			)
			(layer "B.Fab")
		)
		(fp_line
			(start -0.12065 -0.2794)
			(end -0.12065 -0.3048)
			(stroke
				(width 0.1)
				(type default)
			)
			(layer "B.Fab")
		)
		(fp_line
			(start 0.12065 -0.2794)
			(end -0.12065 -0.2794)
			(stroke
				(width 0.1)
				(type default)
			)
			(layer "B.Fab")
		)
		(fp_line
			(start -0.67945 -0.3048)
			(end -0.67945 0.3048)
			(stroke
				(width 0.1)
				(type default)
			)
			(layer "B.Fab")
		)
		(fp_line
			(start -0.12065 -0.3048)
			(end -0.67945 -0.3048)
			(stroke
				(width 0.1)
				(type default)
			)
			(layer "B.Fab")
		)
		(fp_line
			(start 0.12065 -0.305054)
			(end 0.12065 -0.2794)
			(stroke
				(width 0.1)
				(type default)
			)
			(layer "B.Fab")
		)
		(fp_line
			(start 0.67945 -0.305054)
			(end 0.12065 -0.305054)
			(stroke
				(width 0.1)
				(type default)
			)
			(layer "B.Fab")
		)
		(pad "1" smd circle
			(at 0.40005 0 90)
			(size 0 0)
			(layers "B.Cu" "B.Mask" "B.Paste")
			(net "V_DACG_IO")
		)
		(pad "2" smd circle
			(at -0.40005 0 90)
			(size 0 0)
			(layers "B.Cu" "B.Mask" "B.Paste")
			(net "GND")
		)
	)
	(footprint ""
		(layer "B.Cu")
		(at 83.16722 -39.474394 180)
		(property "Reference" "R365"
			(at 0 0 0)
			(layer "B.SilkS")
			(hide yes)
			(effects
				(font
					(size 1.27 1.27)
				)
				(justify mirror)
			)
		)
		(property "Value" ""
			(at 0 0 0)
			(layer "B.Fab")
			(effects
				(font
					(size 1.27 1.27)
				)
				(justify mirror)
			)
		)
		(duplicate_pad_numbers_are_jumpers no)
		(fp_line
			(start 0.7874 0.4064)
			(end 0.7874 -0.4064)
			(stroke
				(width 0.1524)
				(type default)
			)
			(layer "B.SilkS")
		)
		(fp_line
			(start 0.7874 -0.4064)
			(end -0.7874 -0.4064)
			(stroke
				(width 0.1524)
				(type default)
			)
			(layer "B.SilkS")
		)
		(fp_line
			(start -0.7874 0.4064)
			(end 0.7874 0.4064)
			(stroke
				(width 0.1524)
				(type default)
			)
			(layer "B.SilkS")
		)
		(fp_line
			(start -0.7874 -0.4064)
			(end -0.7874 0.4064)
			(stroke
				(width 0.1524)
				(type default)
			)
			(layer "B.SilkS")
		)
		(fp_line
			(start 0.67945 0.3048)
			(end 0.67945 -0.305054)
			(stroke
				(width 0.1)
				(type default)
			)
			(layer "B.Fab")
		)
		(fp_line
			(start 0.67945 -0.305054)
			(end 0.12065 -0.305054)
			(stroke
				(width 0.1)
				(type default)
			)
			(layer "B.Fab")
		)
		(fp_line
			(start 0.12065 0.3048)
			(end 0.67945 0.3048)
			(stroke
				(width 0.1)
				(type default)
			)
			(layer "B.Fab")
		)
		(fp_line
			(start 0.12065 0.2794)
			(end 0.12065 0.3048)
			(stroke
				(width 0.1)
				(type default)
			)
			(layer "B.Fab")
		)
		(fp_line
			(start 0.12065 -0.2794)
			(end -0.12065 -0.2794)
			(stroke
				(width 0.1)
				(type default)
			)
			(layer "B.Fab")
		)
		(fp_line
			(start 0.12065 -0.305054)
			(end 0.12065 -0.2794)
			(stroke
				(width 0.1)
				(type default)
			)
			(layer "B.Fab")
		)
		(fp_line
			(start -0.120396 0.3048)
			(end -0.120396 0.2794)
			(stroke
				(width 0.1)
				(type default)
			)
			(layer "B.Fab")
		)
		(fp_line
			(start -0.120396 0.2794)
			(end 0.12065 0.2794)
			(stroke
				(width 0.1)
				(type default)
			)
			(layer "B.Fab")
		)
		(fp_line
			(start -0.12065 -0.2794)
			(end -0.12065 -0.3048)
			(stroke
				(width 0.1)
				(type default)
			)
			(layer "B.Fab")
		)
		(fp_line
			(start -0.12065 -0.3048)
			(end -0.67945 -0.3048)
			(stroke
				(width 0.1)
				(type default)
			)
			(layer "B.Fab")
		)
		(fp_line
			(start -0.67945 0.3048)
			(end -0.120396 0.3048)
			(stroke
				(width 0.1)
				(type default)
			)
			(layer "B.Fab")
		)
		(fp_line
			(start -0.67945 -0.3048)
			(end -0.67945 0.3048)
			(stroke
				(width 0.1)
				(type default)
			)
			(layer "B.Fab")
		)
		(pad "1" smd circle
			(at 0.40005 0)
			(size 0 0)
			(layers "B.Cu" "B.Mask" "B.Paste")
			(net "M_BMC_DDR4_MWE_N")
		)
		(pad "2" smd circle
			(at -0.40005 0)
			(size 0 0)
			(layers "B.Cu" "B.Mask" "B.Paste")
			(net "P1V2_AUX")
		)
	)
)
